# BASEBOARD_FAB2 (Tioga Pass) — schematic netlist excerpt (pin names and nets, part order shuffled) for the footprints in the layout excerpt that follows; sources: Cadence DE-HDL packaged netlist, KiCad conversion of Wiwynn_Tioga_Pass_MB.brd

C7F10  CAP  0.027UF 16V 10% X7R  pkg 0402  page 231 : A = VR_PVPP_ABC_SS ; B = AGND_PVPP_ABC
C4F7  CAPP  330UF 6.3V 20% POSCAP  pkg 7343LF  page 233 : A = PVPP_GHJ ; B = GND
C4G8  CAP  0.027UF 16V 10% X7R  pkg 0402  page 233 : A = VR_PVPP_GHJ_SS ; B = AGND_PVPP_GHJ

(kicad_pcb
	(version 20260206)
	(generator "pcbnew")
	(generator_version "10.0")
	(general
		(thickness 1.6)
		(legacy_teardrops no)
	)
	(paper "A4")
	(title_block
		(title "Wiwynn_Tioga_Pass_MB.brd")
		(comment 1 "Tioga Pass / footprints 1304-1306 of 4770")
	)
	(layers
		(0 "F.Cu" signal "TOP")
		(4 "In1.Cu" signal "L2GND")
		(6 "In2.Cu" signal "L3")
		(8 "In3.Cu" signal "L4GND")
		(10 "In4.Cu" signal "L5")
		(12 "In5.Cu" signal "L6GND")
		(14 "In6.Cu" signal "L7VCC")
		(16 "In7.Cu" signal "L8VCC")
		(18 "In8.Cu" signal "L9GND")
		(20 "In9.Cu" signal "L10")
		(22 "In10.Cu" signal "L11GND")
		(24 "In11.Cu" signal "L12")
		(26 "In12.Cu" signal "L13GND")
		(2 "B.Cu" signal "BOTTOM")
		(9 "F.Adhes" user "F.Adhesive")
		(11 "B.Adhes" user "B.Adhesive")
		(13 "F.Paste" user "Package Geometry/Pastemask Top")
		(15 "B.Paste" user "Package Geometry/Pastemask Bottom")
		(5 "F.SilkS" user "Ref Des/Silkscreen Top")
		(7 "B.SilkS" user "Ref Des/Silkscreen Bottom")
		(1 "F.Mask" user "Board Geometry/Soldermask Top")
		(3 "B.Mask" user "Board Geometry/Soldermask Bottom")
		(17 "Dwgs.User" user "User.Drawings")
		(19 "Cmts.User" user "User.Comments")
		(21 "Eco1.User" user "User.Eco1")
		(23 "Eco2.User" user "User.Eco2")
		(25 "Edge.Cuts" user "Board Geometry/Outline")
		(27 "Margin" user)
		(31 "F.CrtYd" user "Package Geometry/Place Bound Top")
		(29 "B.CrtYd" user "Package Geometry/Place Bound Bottom")
		(35 "F.Fab" user "Ref Des/Assembly Top")
		(33 "B.Fab" user "Ref Des/Assembly Bottom")
	)
	(footprint ""
		(layer "F.Cu")
		(at 173.355 -8.6995)
		(property "Reference" "C4G8"
			(at 0 0 0)
			(layer "F.SilkS")
			(hide yes)
			(effects
				(font
					(size 1.27 1.27)
				)
			)
		)
		(property "Value" ""
			(at 0 0 0)
			(layer "F.Fab")
			(effects
				(font
					(size 1.27 1.27)
				)
			)
		)
		(duplicate_pad_numbers_are_jumpers no)
		(fp_rect
			(start -0.3048 0.9906)
			(end 0.3048 -0.1016)
			(stroke
				(width 0)
				(type default)
			)
			(fill no)
			(layer "F.CrtYd")
		)
		(fp_line
			(start -0.3048 -0.1016)
			(end -0.3048 0.9906)
			(stroke
				(width 0.1)
				(type default)
			)
			(layer "F.Fab")
		)
		(fp_line
			(start -0.3048 0.9906)
			(end 0.3048 0.9906)
			(stroke
				(width 0.1)
				(type default)
			)
			(layer "F.Fab")
		)
		(fp_line
			(start 0.3048 -0.1016)
			(end -0.3048 -0.1016)
			(stroke
				(width 0.1)
				(type default)
			)
			(layer "F.Fab")
		)
		(fp_line
			(start 0.3048 0.9906)
			(end 0.3048 -0.1016)
			(stroke
				(width 0.1)
				(type default)
			)
			(layer "F.Fab")
		)
		(pad "1" smd rect
			(at 0 0)
			(size 0.508 0.508)
			(layers "F.Cu" "F.Mask" "F.Paste")
			(net "VR_PVPP_GHJ_SS")
		)
		(pad "2" smd rect
			(at 0 0.889)
			(size 0.508 0.508)
			(layers "F.Cu" "F.Mask" "F.Paste")
			(net "AGND_PVPP_GHJ")
		)
		(zone
			(layer "F.Cu")
			(hatch none 0.5)
			(connect_pads
				(clearance 0)
			)
			(min_thickness 0.25)
			(keepout
				(tracks allowed)
				(vias not_allowed)
				(pads allowed)
				(copperpour not_allowed)
				(footprints allowed)
			)
			(placement
				(enabled no)
				(sheetname "")
			)
			(fill
				(thermal_gap 0.5)
				(thermal_bridge_width 0.5)
				(island_removal_mode 0)
			)
			(polygon
				(pts
					(xy 173.101 -8.0645) (xy 173.609 -8.0645) (xy 173.609 -8.4455) (xy 173.101 -8.4455)
				)
			)
		)
		(zone
			(layer "F.Cu")
			(hatch none 0.5)
			(connect_pads
				(clearance 0)
			)
			(min_thickness 0.25)
			(keepout
				(tracks not_allowed)
				(vias allowed)
				(pads allowed)
				(copperpour not_allowed)
				(footprints allowed)
			)
			(placement
				(enabled no)
				(sheetname "")
			)
			(fill
				(thermal_gap 0.5)
				(thermal_bridge_width 0.5)
				(island_removal_mode 0)
			)
			(polygon
				(pts
					(xy 173.101 -8.0645) (xy 173.609 -8.0645) (xy 173.609 -8.4455) (xy 173.101 -8.4455)
				)
			)
		)
	)
	(footprint ""
		(layer "F.Cu")
		(at 166.3446 -26.1747 90)
		(property "Reference" "C4F7"
			(at 2.88163 1.9304 0)
			(unlocked yes)
			(layer "F.SilkS")
			(effects
				(font
					(size 0.7874 0.5842)
					(thickness 0.1524)
				)
				(justify left)
			)
		)
		(property "Value" ""
			(at 0 0 90)
			(layer "F.Fab")
			(effects
				(font
					(size 1.27 1.27)
				)
			)
		)
		(duplicate_pad_numbers_are_jumpers no)
		(fp_line
			(start 2.032 -1.524)
			(end 2.032 1.524)
			(stroke
				(width 0.1524)
				(type default)
			)
			(layer "F.SilkS")
		)
		(fp_line
			(start 1.7272 -1.524)
			(end 2.032 -1.524)
			(stroke
				(width 0.1524)
				(type default)
			)
			(layer "F.SilkS")
		)
		(fp_line
			(start -1.7272 -1.524)
			(end -2.032 -1.524)
			(stroke
				(width 0.1524)
				(type default)
			)
			(layer "F.SilkS")
		)
		(fp_line
			(start -2.032 -1.524)
			(end -2.032 1.524)
			(stroke
				(width 0.1524)
				(type default)
			)
			(layer "F.SilkS")
		)
		(fp_line
			(start 2.2987 -0.2413)
			(end 2.032 -0.2413)
			(stroke
				(width 0.1524)
				(type default)
			)
			(layer "F.SilkS")
		)
		(fp_line
			(start -2.032 -0.2413)
			(end -2.2987 -0.2413)
			(stroke
				(width 0.1524)
				(type default)
			)
			(layer "F.SilkS")
		)
		(fp_line
			(start -2.2987 -0.2413)
			(end -2.2987 7.3533)
			(stroke
				(width 0.1524)
				(type default)
			)
			(layer "F.SilkS")
		)
		(fp_line
			(start 2.032 1.524)
			(end 1.7272 1.524)
			(stroke
				(width 0.1524)
				(type default)
			)
			(layer "F.SilkS")
		)
		(fp_line
			(start -2.032 1.524)
			(end -1.7272 1.524)
			(stroke
				(width 0.1524)
				(type default)
			)
			(layer "F.SilkS")
		)
		(fp_line
			(start 2.2987 7.3533)
			(end 2.2987 -0.2413)
			(stroke
				(width 0.1524)
				(type default)
			)
			(layer "F.SilkS")
		)
		(fp_line
			(start 1.7272 7.3533)
			(end 2.2987 7.3533)
			(stroke
				(width 0.1524)
				(type default)
			)
			(layer "F.SilkS")
		)
		(fp_line
			(start -2.2987 7.3533)
			(end -1.7272 7.3533)
			(stroke
				(width 0.1524)
				(type default)
			)
			(layer "F.SilkS")
		)
		(fp_rect
			(start 2.2987 -0.2413)
			(end -2.2987 7.3533)
			(stroke
				(width 0)
				(type default)
			)
			(fill no)
			(layer "F.CrtYd")
		)
		(fp_line
			(start 2.2987 -0.2413)
			(end 2.2987 7.3533)
			(stroke
				(width 0.1)
				(type default)
			)
			(layer "F.Fab")
		)
		(fp_line
			(start -2.2987 -0.2413)
			(end 2.2987 -0.2413)
			(stroke
				(width 0.1)
				(type default)
			)
			(layer "F.Fab")
		)
		(fp_line
			(start 2.2987 7.3533)
			(end -2.2987 7.3533)
			(stroke
				(width 0.1)
				(type default)
			)
			(layer "F.Fab")
		)
		(fp_line
			(start -2.2987 7.3533)
			(end -2.2987 -0.2413)
			(stroke
				(width 0.1)
				(type default)
			)
			(layer "F.Fab")
		)
		(pad "1" smd rect
			(at 0 0 90)
			(size 2.54 3.048)
			(layers "F.Cu" "F.Mask" "F.Paste")
			(net "PVPP_GHJ")
		)
		(pad "2" smd rect
			(at 0 7.112 90)
			(size 2.54 3.048)
			(layers "F.Cu" "F.Mask" "F.Paste")
			(net "GND")
		)
	)
	(footprint ""
		(layer "F.Cu")
		(at 342.138 -23.749)
		(property "Reference" "C7F10"
			(at 0 0 0)
			(layer "F.SilkS")
			(hide yes)
			(effects
				(font
					(size 1.27 1.27)
				)
			)
		)
		(property "Value" ""
			(at 0 0 0)
			(layer "F.Fab")
			(effects
				(font
					(size 1.27 1.27)
				)
			)
		)
		(duplicate_pad_numbers_are_jumpers no)
		(fp_rect
			(start -0.3048 0.9906)
			(end 0.3048 -0.1016)
			(stroke
				(width 0)
				(type default)
			)
			(fill no)
			(layer "F.CrtYd")
		)
		(fp_line
			(start -0.3048 -0.1016)
			(end -0.3048 0.9906)
			(stroke
				(width 0.1)
				(type default)
			)
			(layer "F.Fab")
		)
		(fp_line
			(start -0.3048 0.9906)
			(end 0.3048 0.9906)
			(stroke
				(width 0.1)
				(type default)
			)
			(layer "F.Fab")
		)
		(fp_line
			(start 0.3048 -0.1016)
			(end -0.3048 -0.1016)
			(stroke
				(width 0.1)
				(type default)
			)
			(layer "F.Fab")
		)
		(fp_line
			(start 0.3048 0.9906)
			(end 0.3048 -0.1016)
			(stroke
				(width 0.1)
				(type default)
			)
			(layer "F.Fab")
		)
		(pad "1" smd rect
			(at 0 0)
			(size 0.508 0.508)
			(layers "F.Cu" "F.Mask" "F.Paste")
			(net "VR_PVPP_ABC_SS")
		)
		(pad "2" smd rect
			(at 0 0.889)
			(size 0.508 0.508)
			(layers "F.Cu" "F.Mask" "F.Paste")
			(net "AGND_PVPP_ABC")
		)
		(zone
			(layer "F.Cu")
			(hatch none 0.5)
			(connect_pads
				(clearance 0)
			)
			(min_thickness 0.25)
			(keepout
				(tracks not_allowed)
				(vias allowed)
				(pads allowed)
				(copperpour not_allowed)
				(footprints allowed)
			)
			(placement
				(enabled no)
				(sheetname "")
			)
			(fill
				(thermal_gap 0.5)
				(thermal_bridge_width 0.5)
				(island_removal_mode 0)
			)
			(polygon
				(pts
					(xy 341.884 -23.114) (xy 342.392 -23.114) (xy 342.392 -23.495) (xy 341.884 -23.495)
				)
			)
		)
		(zone
			(layer "F.Cu")
			(hatch none 0.5)
			(connect_pads
				(clearance 0)
			)
			(min_thickness 0.25)
			(keepout
				(tracks allowed)
				(vias not_allowed)
				(pads allowed)
				(copperpour not_allowed)
				(footprints allowed)
			)
			(placement
				(enabled no)
				(sheetname "")
			)
			(fill
				(thermal_gap 0.5)
				(thermal_bridge_width 0.5)
				(island_removal_mode 0)
			)
			(polygon
				(pts
					(xy 341.884 -23.114) (xy 342.392 -23.114) (xy 342.392 -23.495) (xy 341.884 -23.495)
				)
			)
		)
	)
)
